#ISCELL
  mstr_misc dns *
  *
#ISCELL
  mstr_misc prelim *
  *
#ISCELL
  mstr_symbols cad_note *
  *
#ISCELL
  mstr_symbols intel_corp_bpage *
  *
#ISCELL
  mstr_standard offpage *
  page222_i10
#CELL
  mstr_discrete cap *
  page222_i12
#ISCELL
  mstr_symbols gnd *
  page222_i13
#CELL
  mstr_discrete cap *
  page222_i16
#ISCELL
  mstr_symbols gnd *
  page222_i17
#CELL
  mstr_discrete res *
  page222_i19
#CELL
  mstr_discrete cap *
  page222_i21
#ISCELL
  mstr_symbols gnd *
  page222_i22
#ISCELL
  mstr_symbols gnd *
  page222_i23
#CELL
  mstr_discrete cap *
  page222_i24
#ISCELL
  mstr_symbols gnd *
  page222_i25
#CELL
  mstr_discrete cap *
  page222_i26
#ISCELL
  mstr_symbols gnd *
  page222_i27
#CELL
  mstr_discrete cap *
  page222_i28
#ISCELL
  mstr_symbols gnd *
  page222_i29
#CELL
  mstr_discrete res *
  page222_i30
#CELL
  mstr_vreg mic5166 *
  page222_i31
#CELL
  mstr_discrete res *
  page222_i34
#ISCELL
  mstr_symbols pvddq_def *
  page222_i35
#CELL
  mstr_discrete res *
  page222_i37
#CELL
  mstr_discrete res *
  page222_i38
#ISCELL
  mstr_symbols gnd *
  page222_i39
#CELL
  mstr_discrete cap *
  page222_i40
#ISCELL
  mstr_standard offpage *
  page222_i41
#ISCELL
  mstr_symbols p3v3 *
  page222_i42
#ISCELL
  mstr_symbols p3v3 *
  page222_i43
#ISCELL
  mstr_symbols gnd *
  page222_i45
#CELL
  mstr_discrete cap *
  page222_i46
#CELL
  dev_discrete cap_a *
  page222_i47
#CELL
  dev_discrete cap_a *
  page222_i48
#CELL
  dev_discrete cap_a *
  page222_i49
#CELL
  mstr_discrete res *
  page222_i51
#CELL
  mstr_discrete res *
  page222_i52
#CELL
  mstr_misc shunt *
  page222_i53
#ISCELL
  mstr_symbols pvtt_def *
  page222_i6
#ISCELL
  mstr_symbols gnd *
  page222_i8
#ISCELL
  mstr_symbols pvtt_def *
  page222_i9
